# T6G (Grand Teton) — schematic parts with pin connectivity, parts 8082–8082 of 8303; source: Cadence DE-HDL packaged netlist (pstxprt.dat, pstxnet.dat, pstchip.dat)

U26  GENOA_SP5  SOCKET6096_13568-001 IO  pkg SOCKET6096_93-4X120-45XA  page 37  (pins 3697-4032 of 6096)
  CN31  VSS_CN31  POWER  = GND
  CN32  P2_RXP3  IN  = P5E_CPU1_P2_RX_DP<3>
  CN33  P2_RXN3  IN  = P5E_CPU1_P2_RX_DN<3>
  CN34  VSS_CN34  POWER  = GND
  CN35  VDDCR_CPU1_CN35  POWER  = PVDDCR_CPU1_P1
  CN36  VDDCR_CPU1_CN36  POWER  = PVDDCR_CPU1_P1
  CN40  VDDCR_CPU1_CN40  POWER  = PVDDCR_CPU1_P1
  CN41  VDDCR_CPU1_CN41  POWER  = PVDDCR_CPU1_P1
  CN42  VSS_CN42  POWER  = GND
  CN43  \p0_txn12||sata14_txn\  OUT  = P5E_CPU1_P0_TX_DN<12>
  CN44  \p0_txp12||sata14_txp\  OUT  = P5E_CPU1_P0_TX_DP<12>
  CN45  VSS_CN45  POWER  = GND
  CN46  \p0_txn9||sata11_txn\  OUT  = P5E_CPU1_P0_TX_DN<9>
  CN47  \p0_txp9||sata11_txp\  OUT  = P5E_CPU1_P0_TX_DP<9>
  CN48  VSS_CN48  POWER  = GND
  CN49  \p0_txn3||sata03_txn\  OUT  = P5E_CPU1_P0_TX_DN<3>
  CN50  \p0_txp3||sata03_txp\  OUT  = P5E_CPU1_P0_TX_DP<3>
  CN51  VSS_CN51  POWER  = GND
  CN52  \p0_txn0||sata00_txn\  OUT  = P5E_CPU1_P0_TX_DN<0>
  CN53  \p0_txp0||sata00_txp\  OUT  = P5E_CPU1_P0_TX_DP<0>
  CN54  VSS_CN54  POWER  = GND
  CN55  MCB_DATA13  BI  = M_C_CPU1_SB_DQ<13>
  CN56  VSS_CN56  POWER  = GND
  CN57  MCB_DATA14  BI  = M_C_CPU1_SB_DQ<14>
  CN58  VDDIO_CN58  POWER  = PVDDIO_P1
  CN59  MDB_DATA13  BI  = M_D_CPU1_SB_DQ<13>
  CN60  MDB_DATA14  BI  = M_D_CPU1_SB_DQ<14>
  CN61  VSS_CN61  POWER  = GND
  CN62  MBB_DATA13  BI  = M_B_CPU1_SB_DQ<13>
  CN63  VSS_CN63  POWER  = GND
  CN64  MBB_DATA14  BI  = M_B_CPU1_SB_DQ<14>
  CN65  VDDIO_CN65  POWER  = PVDDIO_P1
  CN66  MFB_DATA13  BI  = M_F_CPU1_SB_DQ<13>
  CN67  MFB_DATA14  BI  = M_F_CPU1_SB_DQ<14>
  CN68  VSS_CN68  POWER  = GND
  CN69  MEB_DATA13  BI  = M_E_CPU1_SB_DQ<13>
  CN70  VSS_CN70  POWER  = GND
  CN71  MEB_DATA14  BI  = M_E_CPU1_SB_DQ<14>
  CN72  VDDIO_CN72  POWER  = PVDDIO_P1
  CN73  MAB_DATA13  BI  = M_A_CPU1_SB_DQ<13>
  CN74  MAB_DATA14  BI  = M_A_CPU1_SB_DQ<14>
  CN75  VSS_CN75  POWER  = GND
  CP2  MGB_DATA16  BI  = M_G_CPU1_SB_DQ<16>
  CP3  VSS_CP3  POWER  = GND
  CP4  MGB_DATA15  BI  = M_G_CPU1_SB_DQ<15>
  CP5  VSS_CP5  POWER  = GND
  CP6  MKB_DATA16  BI  = M_K_CPU1_SB_DQ<16>
  CP7  MKB_DATA15  BI  = M_K_CPU1_SB_DQ<15>
  CP8  VSS_CP8  POWER  = GND
  CP9  MLB_DATA16  BI  = M_L_CPU1_SB_DQ<16>
  CP10  VSS_CP10  POWER  = GND
  CP11  MLB_DATA15  BI  = M_L_CPU1_SB_DQ<15>
  CP12  VSS_CP12  POWER  = GND
  CP13  MHB_DATA16  BI  = M_H_CPU1_SB_DQ<16>
  CP14  MHB_DATA15  BI  = M_H_CPU1_SB_DQ<15>
  CP15  VSS_CP15  POWER  = GND
  CP16  MJB_DATA16  BI  = M_J_CPU1_SB_DQ<16>
  CP17  VSS_CP17  POWER  = GND
  CP18  MJB_DATA15  BI  = M_J_CPU1_SB_DQ<15>
  CP19  VSS_CP19  POWER  = GND
  CP20  MIB_DATA16  BI  = M_I_CPU1_SB_DQ<16>
  CP21  MIB_DATA15  BI  = M_I_CPU1_SB_DQ<15>
  CP22  VSS_CP22  POWER  = GND
  CP23  VDDCR_CPU1_CP23  POWER  = PVDDCR_CPU1_P1
  CP24  VDDCR_CPU1_CP24  POWER  = PVDDCR_CPU1_P1
  CP25  VSS_CP25  POWER  = GND
  CP26  VDDCR_CPU1_CP26  POWER  = PVDDCR_CPU1_P1
  CP27  VDDCR_CPU1_CP27  POWER  = PVDDCR_CPU1_P1
  CP28  VSS_CP28  POWER  = GND
  CP29  VDDCR_CPU1_CP29  POWER  = PVDDCR_CPU1_P1
  CP30  VDDCR_CPU1_CP30  POWER  = PVDDCR_CPU1_P1
  CP31  VSS_CP31  POWER  = GND
  CP32  VDDCR_CPU1_CP32  POWER  = PVDDCR_CPU1_P1
  CP33  VDDCR_CPU1_CP33  POWER  = PVDDCR_CPU1_P1
  CP34  VSS_CP34  POWER  = GND
  CP35  P2_RXP1  IN  = P5E_CPU1_P2_RX_DP<1>
  CP36  P2_RXN1  IN  = P5E_CPU1_P2_RX_DN<1>
  CP37  VSS_CP37  POWER  = GND
  CP39  VSS_CP39  POWER  = GND
  CP40  \p0_txn14||sata16_txn\  OUT  = P5E_CPU1_P0_TX_DN<14>
  CP41  \p0_txp14||sata16_txp\  OUT  = P5E_CPU1_P0_TX_DP<14>
  CP42  VSS_CP42  POWER  = GND
  CP43  VDDCR_CPU1_CP43  POWER  = PVDDCR_CPU1_P1
  CP44  VDDCR_CPU1_CP44  POWER  = PVDDCR_CPU1_P1
  CP45  VSS_CP45  POWER  = GND
  CP46  VDDCR_CPU1_CP46  POWER  = PVDDCR_CPU1_P1
  CP47  VDDCR_CPU1_CP47  POWER  = PVDDCR_CPU1_P1
  CP48  VSS_CP48  POWER  = GND
  CP49  VDDCR_CPU1_CP49  POWER  = PVDDCR_CPU1_P1
  CP50  VDDCR_CPU1_CP50  POWER  = PVDDCR_CPU1_P1
  CP51  VSS_CP51  POWER  = GND
  CP52  VDDCR_CPU1_CP52  POWER  = PVDDCR_CPU1_P1
  CP53  VDDCR_CPU1_CP53  POWER  = PVDDCR_CPU1_P1
  CP54  VSS_CP54  POWER  = GND
  CP55  MCB_DATA15  BI  = M_C_CPU1_SB_DQ<15>
  CP56  MCB_DATA16  BI  = M_C_CPU1_SB_DQ<16>
  CP57  VSS_CP57  POWER  = GND
  CP58  MDB_DATA15  BI  = M_D_CPU1_SB_DQ<15>
  CP59  VSS_CP59  POWER  = GND
  CP60  MDB_DATA16  BI  = M_D_CPU1_SB_DQ<16>
  CP61  VSS_CP61  POWER  = GND
  CP62  MBB_DATA15  BI  = M_B_CPU1_SB_DQ<15>
  CP63  MBB_DATA16  BI  = M_B_CPU1_SB_DQ<16>
  CP64  VSS_CP64  POWER  = GND
  CP65  MFB_DATA15  BI  = M_F_CPU1_SB_DQ<15>
  CP66  VSS_CP66  POWER  = GND
  CP67  MFB_DATA16  BI  = M_F_CPU1_SB_DQ<16>
  CP68  VSS_CP68  POWER  = GND
  CP69  MEB_DATA15  BI  = M_E_CPU1_SB_DQ<15>
  CP70  MEB_DATA16  BI  = M_E_CPU1_SB_DQ<16>
  CP71  VSS_CP71  POWER  = GND
  CP72  MAB_DATA15  BI  = M_A_CPU1_SB_DQ<15>
  CP73  VSS_CP73  POWER  = GND
  CP74  MAB_DATA16  BI  = M_A_CPU1_SB_DQ<16>
  CR1  VSS_CR1  POWER  = GND
  CR2  MGB_DATA18  BI  = M_G_CPU1_SB_DQ<18>
  CR3  MGB_DATA17  BI  = M_G_CPU1_SB_DQ<17>
  CR4  VSS_CR4  POWER  = GND
  CR5  MKB_DATA18  BI  = M_K_CPU1_SB_DQ<18>
  CR6  VSS_CR6  POWER  = GND
  CR7  MKB_DATA17  BI  = M_K_CPU1_SB_DQ<17>
  CR8  VSS_CR8  POWER  = GND
  CR9  MLB_DATA18  BI  = M_L_CPU1_SB_DQ<18>
  CR10  MLB_DATA17  BI  = M_L_CPU1_SB_DQ<17>
  CR11  VSS_CR11  POWER  = GND
  CR12  MHB_DATA18  BI  = M_H_CPU1_SB_DQ<18>
  CR13  VSS_CR13  POWER  = GND
  CR14  MHB_DATA17  BI  = M_H_CPU1_SB_DQ<17>
  CR15  VSS_CR15  POWER  = GND
  CR16  MJB_DATA18  BI  = M_J_CPU1_SB_DQ<18>
  CR17  MJB_DATA17  BI  = M_J_CPU1_SB_DQ<17>
  CR18  VSS_CR18  POWER  = GND
  CR19  MIB_DATA18  BI  = M_I_CPU1_SB_DQ<18>
  CR20  VSS_CR20  POWER  = GND
  CR21  MIB_DATA17  BI  = M_I_CPU1_SB_DQ<17>
  CR22  VSS_CR22  POWER  = GND
  CR23  P2_RXP14  IN  = P5E_CPU1_P2_RX_DP<14>
  CR24  P2_RXN14  IN  = P5E_CPU1_P2_RX_DN<14>
  CR25  VSS_CR25  POWER  = GND
  CR26  P2_RXP11  IN  = P5E_CPU1_P2_RX_DP<11>
  CR27  P2_RXN11  IN  = P5E_CPU1_P2_RX_DN<11>
  CR28  VSS_CR28  POWER  = GND
  CR29  P2_RXP8  IN  = P5E_CPU1_P2_RX_DP<8>
  CR30  P2_RXN8  IN  = P5E_CPU1_P2_RX_DN<8>
  CR31  VSS_CR31  POWER  = GND
  CR32  P2_RXP5  IN  = P5E_CPU1_P2_RX_DP<5>
  CR33  P2_RXN5  IN  = P5E_CPU1_P2_RX_DN<5>
  CR34  VSS_CR34  POWER  = GND
  CR35  VSS_CR35  POWER  = GND
  CR36  VSS_CR36  POWER  = GND
  CR40  VSS_CR40  POWER  = GND
  CR41  VSS_CR41  POWER  = GND
  CR42  VSS_CR42  POWER  = GND
  CR43  \p0_txn10||sata12_txn\  OUT  = P5E_CPU1_P0_TX_DN<10>
  CR44  \p0_txp10||sata12_txp\  OUT  = P5E_CPU1_P0_TX_DP<10>
  CR45  VSS_CR45  POWER  = GND
  CR46  \p0_txn7||sata07_txn\  OUT  = P5E_CPU1_P0_TX_DN<7>
  CR47  \p0_txp7||sata07_txp\  OUT  = P5E_CPU1_P0_TX_DP<7>
  CR48  VSS_CR48  POWER  = GND
  CR49  \p0_txn4||sata04_txn\  OUT  = P5E_CPU1_P0_TX_DN<4>
  CR50  \p0_txp4||sata04_txp\  OUT  = P5E_CPU1_P0_TX_DP<4>
  CR51  VSS_CR51  POWER  = GND
  CR52  \p0_txn1||sata01_txn\  OUT  = P5E_CPU1_P0_TX_DN<1>
  CR53  \p0_txp1||sata01_txp\  OUT  = P5E_CPU1_P0_TX_DP<1>
  CR54  VSS_CR54  POWER  = GND
  CR55  MCB_DATA17  BI  = M_C_CPU1_SB_DQ<17>
  CR56  VSS_CR56  POWER  = GND
  CR57  MCB_DATA18  BI  = M_C_CPU1_SB_DQ<18>
  CR58  VSS_CR58  POWER  = GND
  CR59  MDB_DATA17  BI  = M_D_CPU1_SB_DQ<17>
  CR60  MDB_DATA18  BI  = M_D_CPU1_SB_DQ<18>
  CR61  VSS_CR61  POWER  = GND
  CR62  MBB_DATA17  BI  = M_B_CPU1_SB_DQ<17>
  CR63  VSS_CR63  POWER  = GND
  CR64  MBB_DATA18  BI  = M_B_CPU1_SB_DQ<18>
  CR65  VSS_CR65  POWER  = GND
  CR66  MFB_DATA17  BI  = M_F_CPU1_SB_DQ<17>
  CR67  MFB_DATA18  BI  = M_F_CPU1_SB_DQ<18>
  CR68  VSS_CR68  POWER  = GND
  CR69  MEB_DATA17  BI  = M_E_CPU1_SB_DQ<17>
  CR70  VSS_CR70  POWER  = GND
  CR71  MEB_DATA18  BI  = M_E_CPU1_SB_DQ<18>
  CR72  VSS_CR72  POWER  = GND
  CR73  MAB_DATA17  BI  = M_A_CPU1_SB_DQ<17>
  CR74  MAB_DATA18  BI  = M_A_CPU1_SB_DQ<18>
  CR75  VSS_CR75  POWER  = GND
  CT2  MGB_DQS_H2  BI  = M_G_CPU1_SB_DQS_DP<2>
  CT3  VSS_CT3  POWER  = GND
  CT4  MGB_DATA19  BI  = M_G_CPU1_SB_DQ<19>
  CT5  VDD_11_S3_CT5  POWER  = PVDD11_S3_P1
  CT6  MKB_DQS_H2  BI  = M_K_CPU1_SB_DQS_DP<2>
  CT7  MKB_DATA19  BI  = M_K_CPU1_SB_DQ<19>
  CT8  VSS_CT8  POWER  = GND
  CT9  MLB_DQS_H2  BI  = M_L_CPU1_SB_DQS_DP<2>
  CT10  VSS_CT10  POWER  = GND
  CT11  MLB_DATA19  BI  = M_L_CPU1_SB_DQ<19>
  CT12  VDD_11_S3_CT12  POWER  = PVDD11_S3_P1
  CT13  MHB_DQS_H2  BI  = M_H_CPU1_SB_DQS_DP<2>
  CT14  MHB_DATA19  BI  = M_H_CPU1_SB_DQ<19>
  CT15  VSS_CT15  POWER  = GND
  CT16  MJB_DQS_H2  BI  = M_J_CPU1_SB_DQS_DP<2>
  CT17  VSS_CT17  POWER  = GND
  CT18  MJB_DATA19  BI  = M_J_CPU1_SB_DQ<19>
  CT19  VDD_11_S3_CT19  POWER  = PVDD11_S3_P1
  CT20  MIB_DQS_H2  BI  = M_I_CPU1_SB_DQS_DP<2>
  CT21  MIB_DATA19  BI  = M_I_CPU1_SB_DQ<19>
  CT22  VDD_11_S3_CT22  POWER  = PVDD11_S3_P1
  CT23  VSS_CT23  POWER  = GND
  CT24  VSS_CT24  POWER  = GND
  CT25  VSS_CT25  POWER  = GND
  CT26  VSS_CT26  POWER  = GND
  CT27  VSS_CT27  POWER  = GND
  CT28  VSS_CT28  POWER  = GND
  CT29  VSS_CT29  POWER  = GND
  CT30  VSS_CT30  POWER  = GND
  CT31  VSS_CT31  POWER  = GND
  CT32  VSS_CT32  POWER  = GND
  CT33  VSS_CT33  POWER  = GND
  CT34  VSS_CT34  POWER  = GND
  CT35  P2_RXP2  IN  = P5E_CPU1_P2_RX_DP<2>
  CT36  P2_RXN2  IN  = P5E_CPU1_P2_RX_DN<2>
  CT37  VSS_CT37  POWER  = GND
  CT39  VSS_CT39  POWER  = GND
  CT40  \p0_txn13||sata15_txn\  OUT  = P5E_CPU1_P0_TX_DN<13>
  CT41  \p0_txp13||sata15_txp\  OUT  = P5E_CPU1_P0_TX_DP<13>
  CT42  VSS_CT42  POWER  = GND
  CT43  VSS_CT43  POWER  = GND
  CT44  VSS_CT44  POWER  = GND
  CT45  VSS_CT45  POWER  = GND
  CT46  VSS_CT46  POWER  = GND
  CT47  VSS_CT47  POWER  = GND
  CT48  VSS_CT48  POWER  = GND
  CT49  VSS_CT49  POWER  = GND
  CT50  VSS_CT50  POWER  = GND
  CT51  VSS_CT51  POWER  = GND
  CT52  VSS_CT52  POWER  = GND
  CT53  VSS_CT53  POWER  = GND
  CT54  VDDIO_CT54  POWER  = PVDDIO_P1
  CT55  MCB_DATA19  BI  = M_C_CPU1_SB_DQ<19>
  CT56  MCB_DQS_H2  BI  = M_C_CPU1_SB_DQS_DP<2>
  CT57  VDDIO_CT57  POWER  = PVDDIO_P1
  CT58  MDB_DATA19  BI  = M_D_CPU1_SB_DQ<19>
  CT59  VSS_CT59  POWER  = GND
  CT60  MDB_DQS_H2  BI  = M_D_CPU1_SB_DQS_DP<2>
  CT61  VSS_CT61  POWER  = GND
  CT62  MBB_DATA19  BI  = M_B_CPU1_SB_DQ<19>
  CT63  MBB_DQS_H2  BI  = M_B_CPU1_SB_DQS_DP<2>
  CT64  VDDIO_CT64  POWER  = PVDDIO_P1
  CT65  MFB_DATA19  BI  = M_F_CPU1_SB_DQ<19>
  CT66  VSS_CT66  POWER  = GND
  CT67  MFB_DQS_H2  BI  = M_F_CPU1_SB_DQS_DP<2>
  CT68  VSS_CT68  POWER  = GND
  CT69  MEB_DATA19  BI  = M_E_CPU1_SB_DQ<19>
  CT70  MEB_DQS_H2  BI  = M_E_CPU1_SB_DQS_DP<2>
  CT71  VDDIO_CT71  POWER  = PVDDIO_P1
  CT72  MAB_DATA19  BI  = M_A_CPU1_SB_DQ<19>
  CT73  VSS_CT73  POWER  = GND
  CT74  MAB_DQS_H2  BI  = M_A_CPU1_SB_DQS_DP<2>
  CU1  VSS_CU1  POWER  = GND
  CU2  MGB_DQS_L2  BI  = M_G_CPU1_SB_DQS_DN<2>
  CU3  MGB_DQS_L7  BI  = M_G_CPU1_SB_DQS_DN<7>
  CU4  VSS_CU4  POWER  = GND
  CU5  MKB_DQS_L2  BI  = M_K_CPU1_SB_DQS_DN<2>
  CU6  VSS_CU6  POWER  = GND
  CU7  MKB_DQS_L7  BI  = M_K_CPU1_SB_DQS_DN<7>
  CU8  VSS_CU8  POWER  = GND
  CU9  MLB_DQS_L2  BI  = M_L_CPU1_SB_DQS_DN<2>
  CU10  MLB_DQS_L7  BI  = M_L_CPU1_SB_DQS_DN<7>
  CU11  VSS_CU11  POWER  = GND
  CU12  MHB_DQS_L2  BI  = M_H_CPU1_SB_DQS_DN<2>
  CU13  VSS_CU13  POWER  = GND
  CU14  MHB_DQS_L7  BI  = M_H_CPU1_SB_DQS_DN<7>
  CU15  VSS_CU15  POWER  = GND
  CU16  MJB_DQS_L2  BI  = M_J_CPU1_SB_DQS_DN<2>
  CU17  MJB_DQS_L7  BI  = M_J_CPU1_SB_DQS_DN<7>
  CU18  VSS_CU18  POWER  = GND
  CU19  MIB_DQS_L2  BI  = M_I_CPU1_SB_DQS_DN<2>
  CU20  VSS_CU20  POWER  = GND
  CU21  MIB_DQS_L7  BI  = M_I_CPU1_SB_DQS_DN<7>
  CU22  VSS_CU22  POWER  = GND
  CU23  P3_RXP15  IN  = P5E_CPU1_P3_RX_DP<15>
  CU24  P3_RXN15  IN  = P5E_CPU1_P3_RX_DN<15>
  CU25  VSS_CU25  POWER  = GND
  CU26  P2_RXP10  IN  = P5E_CPU1_P2_RX_DP<10>
  CU27  P2_RXN10  IN  = P5E_CPU1_P2_RX_DN<10>
  CU28  VSS_CU28  POWER  = GND
  CU29  P2_RXP7  IN  = P5E_CPU1_P2_RX_DP<7>
  CU30  P2_RXN7  IN  = P5E_CPU1_P2_RX_DN<7>
  CU31  VSS_CU31  POWER  = GND
  CU32  P2_RXP4  IN  = P5E_CPU1_P2_RX_DP<4>
  CU33  P2_RXN4  IN  = P5E_CPU1_P2_RX_DN<4>
  CU34  VSS_CU34  POWER  = GND
  CU35  VDDCR_CPU1_CU35  POWER  = PVDDCR_CPU1_P1
  CU36  VDDCR_CPU1_CU36  POWER  = PVDDCR_CPU1_P1
  CU40  VDDCR_CPU1_CU40  POWER  = PVDDCR_CPU1_P1
  CU41  VDDCR_CPU1_CU41  POWER  = PVDDCR_CPU1_P1
  CU42  VSS_CU42  POWER  = GND
  CU43  \p0_txn11||sata13_txn\  OUT  = P5E_CPU1_P0_TX_DN<11>
  CU44  \p0_txp11||sata13_txp\  OUT  = P5E_CPU1_P0_TX_DP<11>
  CU45  VSS_CU45  POWER  = GND
  CU46  \p0_txn8||sata10_txn\  OUT  = P5E_CPU1_P0_TX_DN<8>
  CU47  \p0_txp8||sata10_txp\  OUT  = P5E_CPU1_P0_TX_DP<8>
  CU48  VSS_CU48  POWER  = GND
  CU49  \p0_txn5||sata05_txn\  OUT  = P5E_CPU1_P0_TX_DN<5>
  CU50  \p0_txp5||sata05_txp\  OUT  = P5E_CPU1_P0_TX_DP<5>
  CU51  VSS_CU51  POWER  = GND
  CU52  P1_TXN0  OUT  = P5E_CPU1_P1_TX_DN<0>
  CU53  P1_TXP0  OUT  = P5E_CPU1_P1_TX_DP<0>
  CU54  VSS_CU54  POWER  = GND
  CU55  MCB_DQS_L7  BI  = M_C_CPU1_SB_DQS_DN<7>
  CU56  VSS_CU56  POWER  = GND
  CU57  MCB_DQS_L2  BI  = M_C_CPU1_SB_DQS_DN<2>
  CU58  VSS_CU58  POWER  = GND
  CU59  MDB_DQS_L7  BI  = M_D_CPU1_SB_DQS_DN<7>
  CU60  MDB_DQS_L2  BI  = M_D_CPU1_SB_DQS_DN<2>
  CU61  VSS_CU61  POWER  = GND
  CU62  MBB_DQS_L7  BI  = M_B_CPU1_SB_DQS_DN<7>
  CU63  VSS_CU63  POWER  = GND
  CU64  MBB_DQS_L2  BI  = M_B_CPU1_SB_DQS_DN<2>
  CU65  VSS_CU65  POWER  = GND
  CU66  MFB_DQS_L7  BI  = M_F_CPU1_SB_DQS_DN<7>
  CU67  MFB_DQS_L2  BI  = M_F_CPU1_SB_DQS_DN<2>
  CU68  VSS_CU68  POWER  = GND
  CU69  MEB_DQS_L7  BI  = M_E_CPU1_SB_DQS_DN<7>
  CU70  VSS_CU70  POWER  = GND
  CU71  MEB_DQS_L2  BI  = M_E_CPU1_SB_DQS_DN<2>
  CU72  VSS_CU72  POWER  = GND
  CU73  MAB_DQS_L7  BI  = M_A_CPU1_SB_DQS_DN<7>
  CU74  MAB_DQS_L2  BI  = M_A_CPU1_SB_DQS_DN<2>
  CU75  VSS_CU75  POWER  = GND
  CV2  MGB_DATA20  BI  = M_G_CPU1_SB_DQ<20>
  CV3  VSS_CV3  POWER  = GND
  CV4  MGB_DQS_H7  BI  = M_G_CPU1_SB_DQS_DP<7>
  CV5  VSS_CV5  POWER  = GND
  CV6  MKB_DATA20  BI  = M_K_CPU1_SB_DQ<20>
  CV7  MKB_DQS_H7  BI  = M_K_CPU1_SB_DQS_DP<7>
